(kicad_pcb
	(version 20240108)
	(generator "pcbnew")
	(generator_version "8.0")
	(general
		(thickness 1.62)
		(legacy_teardrops no)
	)
	(paper "A4")
	(title_block
		(title "Jetson Orin Baseboard")
		(date "2025-03-12")
		(rev "1.3.4")
		(company "Antmicro Ltd")
		(comment 1 "www.antmicro.com")
		(comment 9 "footprints 192-195 of 677")
	)
	(layers
		(0 "F.Cu" signal)
		(1 "In1.Cu" signal)
		(2 "In2.Cu" signal)
		(3 "In3.Cu" signal)
		(4 "In4.Cu" jumper)
		(5 "In5.Cu" signal)
		(6 "In6.Cu" signal)
		(31 "B.Cu" signal)
		(32 "B.Adhes" user "B.Adhesive")
		(33 "F.Adhes" user "F.Adhesive")
		(34 "B.Paste" user)
		(35 "F.Paste" user)
		(36 "B.SilkS" user "B.Silkscreen")
		(37 "F.SilkS" user "F.Silkscreen")
		(38 "B.Mask" user)
		(39 "F.Mask" user)
		(40 "Dwgs.User" user "User.Drawings")
		(41 "Cmts.User" user "User.Comments")
		(42 "Eco1.User" user "User.Eco1")
		(43 "Eco2.User" user "User.Eco2")
		(44 "Edge.Cuts" user)
		(45 "Margin" user)
		(46 "B.CrtYd" user "B.Courtyard")
		(47 "F.CrtYd" user "F.Courtyard")
		(48 "B.Fab" user)
		(49 "F.Fab" user)
	)
	(footprint "antmicro-footprints:TP_SMD_0.75mm"
		(layer "F.Cu")
		(at 102.95 86.925 180)
		(property "Reference" "TP21"
			(at -0.175 -0.4508 180)
			(layer "F.SilkS")
			(effects
				(font
					(size 0.7 0.7)
					(thickness 0.15)
				)
				(justify left bottom)
			)
		)
		(property "Value" "TP_0.75mm_SMD"
			(at 0 1.2 180)
			(layer "F.Fab")
			(effects
				(font
					(size 0.7 0.7)
					(thickness 0.15)
				)
				(justify left bottom)
			)
		)
		(property "Footprint" "antmicro-footprints:TP_SMD_0.75mm"
			(at 0 0 180)
			(layer "F.Fab")
			(hide yes)
			(effects
				(font
					(size 1.27 1.27)
					(thickness 0.15)
				)
			)
		)
		(property "Author" "Antmicro"
			(at 205.9 173.85 0)
			(layer "F.Fab")
			(hide yes)
			(effects
				(font
					(size 1 1)
					(thickness 0.15)
				)
			)
		)
		(property "License" "Apache-2.0"
			(at 205.9 173.85 0)
			(layer "F.Fab")
			(hide yes)
			(effects
				(font
					(size 1 1)
					(thickness 0.15)
				)
			)
		)
		(property "MPN" ""
			(at 205.9 173.85 0)
			(layer "F.Fab")
			(hide yes)
			(effects
				(font
					(size 1 1)
					(thickness 0.15)
				)
			)
		)
		(property "Manufacturer" ""
			(at 205.9 173.85 0)
			(layer "F.Fab")
			(hide yes)
			(effects
				(font
					(size 1 1)
					(thickness 0.15)
				)
			)
		)
		(sheetname "HDMI")
		(sheetfile "hdmi.kicad_sch")
		(attr exclude_from_pos_files exclude_from_bom)
		(fp_circle
			(center 0 0)
			(end 0.475 0)
			(stroke
				(width 0.05)
				(type default)
			)
			(fill none)
			(layer "F.CrtYd")
		)
		(fp_text user "Author: Antmicro"
			(at -0.4 3.901 180)
			(layer "F.Fab")
			(hide yes)
			(effects
				(font
					(size 0.7 0.7)
					(thickness 0.15)
				)
				(justify left bottom)
			)
		)
		(fp_text user "License: Apache-2.0"
			(at -0.4 5.101 180)
			(layer "F.Fab")
			(hide yes)
			(effects
				(font
					(size 0.7 0.7)
					(thickness 0.15)
				)
				(justify left bottom)
			)
		)
		(fp_text user "${REFERENCE}"
			(at -0.4 2.7 180)
			(layer "F.Fab")
			(hide yes)
			(effects
				(font
					(size 0.7 0.7)
					(thickness 0.15)
				)
				(justify left bottom)
			)
		)
		(pad "1" smd circle
			(at 0 0 180)
			(size 0.75 0.75)
			(layers "F.Cu" "F.Mask")
			(net 428 "DP1_HPD")
			(pinfunction "1")
			(pintype "passive")
		)
	)
	(footprint "antmicro-footprints:LED_0603_1608Metric_G"
		(layer "F.Cu")
		(at 68.8 127.15 90)
		(descr "LED SMD 0603 Green")
		(tags "LED SMD 0603 Green")
		(property "Reference" "D9"
			(at -1.175 -2 180)
			(layer "F.SilkS")
			(effects
				(font
					(size 0.7 0.7)
					(thickness 0.15)
				)
				(justify left bottom)
			)
		)
		(property "Value" "LED_G_0603_LTST-C190GKT"
			(at 2.2 0.8 90)
			(layer "F.Fab")
			(effects
				(font
					(size 0.7 0.7)
					(thickness 0.15)
				)
				(justify left bottom)
			)
		)
		(property "Footprint" "antmicro-footprints:LED_0603_1608Metric_G"
			(at 0 0 90)
			(layer "F.Fab")
			(hide yes)
			(effects
				(font
					(size 1.27 1.27)
					(thickness 0.15)
				)
			)
		)
		(property "Datasheet" "https://media.digikey.com/pdf/Data%20Sheets/Lite-On%20PDFs/LTST-C190GKT.pdf"
			(at 0 0 90)
			(layer "F.Fab")
			(hide yes)
			(effects
				(font
					(size 1.27 1.27)
					(thickness 0.15)
				)
			)
		)
		(property "Author" "Antmicro"
			(at 195.95 58.35 0)
			(layer "F.Fab")
			(hide yes)
			(effects
				(font
					(size 1 1)
					(thickness 0.15)
				)
			)
		)
		(property "Color" "Green"
			(at 195.95 58.35 0)
			(layer "F.Fab")
			(hide yes)
			(effects
				(font
					(size 1 1)
					(thickness 0.15)
				)
			)
		)
		(property "License" "Apache-2.0"
			(at 195.95 58.35 0)
			(layer "F.Fab")
			(hide yes)
			(effects
				(font
					(size 1 1)
					(thickness 0.15)
				)
			)
		)
		(property "MPN" "LTST-C190GKT"
			(at 195.95 58.35 0)
			(layer "F.Fab")
			(hide yes)
			(effects
				(font
					(size 1 1)
					(thickness 0.15)
				)
			)
		)
		(property "Manufacturer" "Lite-On"
			(at 195.95 58.35 0)
			(layer "F.Fab")
			(hide yes)
			(effects
				(font
					(size 1 1)
					(thickness 0.15)
				)
			)
		)
		(sheetname "USB Debug, DP")
		(sheetfile "usb.kicad_sch")
		(attr smd)
		(fp_line
			(start 0.22 -0.35)
			(end -0.22 -0.35)
			(stroke
				(width 0.15)
				(type solid)
			)
			(layer "F.SilkS")
		)
		(fp_line
			(start -1.18 -0.319)
			(end -1.18 0.321)
			(stroke
				(width 0.15)
				(type solid)
			)
			(layer "F.SilkS")
		)
		(fp_line
			(start 0.105328 0.001008)
			(end 0.24 0.001)
			(stroke
				(width 0.1)
				(type solid)
			)
			(layer "F.SilkS")
		)
		(fp_line
			(start -0.094672 0.001008)
			(end 0.105328 -0.198992)
			(stroke
				(width 0.1)
				(type solid)
			)
			(layer "F.SilkS")
		)
		(fp_line
			(start -0.094672 0.001008)
			(end -0.24 0.001008)
			(stroke
				(width 0.1)
				(type solid)
			)
			(layer "F.SilkS")
		)
		(fp_line
			(start 0.105328 0.201008)
			(end 0.105328 -0.198992)
			(stroke
				(width 0.1)
				(type solid)
			)
			(layer "F.SilkS")
		)
		(fp_line
			(start 0.105328 0.201008)
			(end -0.094672 0.001008)
			(stroke
				(width 0.1)
				(type solid)
			)
			(layer "F.SilkS")
		)
		(fp_line
			(start -0.094672 0.201008)
			(end -0.094672 -0.198992)
			(stroke
				(width 0.1)
				(type solid)
			)
			(layer "F.SilkS")
		)
		(fp_line
			(start 0.22 0.35)
			(end -0.22 0.35)
			(stroke
				(width 0.15)
				(type solid)
			)
			(layer "F.SilkS")
		)
		(fp_rect
			(start 1.25 0.65)
			(end -1.25 -0.65)
			(stroke
				(width 0.05)
				(type solid)
			)
			(fill none)
			(layer "F.CrtYd")
		)
		(fp_line
			(start 0.201 -0.202)
			(end -0.101 0)
			(stroke
				(width 0.15)
				(type solid)
			)
			(layer "F.Fab")
		)
		(fp_line
			(start -0.199 -0.202)
			(end -0.199 0.1)
			(stroke
				(width 0.15)
				(type solid)
			)
			(layer "F.Fab")
		)
		(fp_line
			(start 0.599 0)
			(end 0.201 0)
			(stroke
				(width 0.15)
				(type solid)
			)
			(layer "F.Fab")
		)
		(fp_line
			(start 0.201 0)
			(end 0.201 -0.202)
			(stroke
				(width 0.15)
				(type solid)
			)
			(layer "F.Fab")
		)
		(fp_line
			(start -0.101 0)
			(end 0.201 0.2)
			(stroke
				(width 0.15)
				(type solid)
			)
			(layer "F.Fab")
		)
		(fp_line
			(start -0.199 0)
			(end -0.597 0)
			(stroke
				(width 0.15)
				(type solid)
			)
			(layer "F.Fab")
		)
		(fp_line
			(start 0.201 0.2)
			(end 0.201 0)
			(stroke
				(width 0.15)
				(type solid)
			)
			(layer "F.Fab")
		)
		(fp_line
			(start -0.199 0.2)
			(end -0.199 0.1)
			(stroke
				(width 0.15)
				(type solid)
			)
			(layer "F.Fab")
		)
		(fp_rect
			(start 0.848 0.4)
			(end -0.85 -0.402)
			(stroke
				(width 0.15)
				(type solid)
			)
			(fill none)
			(layer "F.Fab")
		)
		(fp_text user "License: Apache-2.0"
			(at -1.4224 3.599 90)
			(layer "F.Fab")
			(hide yes)
			(effects
				(font
					(size 0.7 0.7)
					(thickness 0.15)
				)
				(justify left bottom)
			)
		)
		(fp_text user "${REFERENCE}"
			(at -1.4224 5.999 90)
			(layer "F.Fab")
			(hide yes)
			(effects
				(font
					(size 0.7 0.7)
					(thickness 0.15)
				)
				(justify left bottom)
			)
		)
		(fp_text user "Author: Antmicro"
			(at -1.4224 4.799 90)
			(layer "F.Fab")
			(hide yes)
			(effects
				(font
					(size 0.7 0.7)
					(thickness 0.15)
				)
				(justify left bottom)
			)
		)
		(pad "1" smd roundrect
			(at -0.7 0 270)
			(size 0.8 1)
			(layers "F.Cu" "F.Paste" "F.Mask")
			(roundrect_rratio 0.2)
			(net 1 "GND")
			(pinfunction "C")
			(pintype "passive")
		)
		(pad "2" smd roundrect
			(at 0.7 0 270)
			(size 0.8 1)
			(layers "F.Cu" "F.Paste" "F.Mask")
			(roundrect_rratio 0.2)
			(net 147 "Net-(D9-A)")
			(pinfunction "A")
			(pintype "passive")
		)
	)
	(footprint "antmicro-footprints:R_0402_1005Metric"
		(layer "F.Cu")
		(at 104.2 115.8 -90)
		(descr "Resistor SMD 0402")
		(tags "resistor SMD 0402")
		(property "Reference" "R136"
			(at -0.9 -0.45 -90)
			(layer "F.SilkS")
			(effects
				(font
					(size 0.7 0.7)
					(thickness 0.15)
				)
				(justify left bottom)
			)
		)
		(property "Value" "R_10k_0402"
			(at 0 1.4 -90)
			(layer "F.Fab")
			(effects
				(font
					(size 0.7 0.7)
					(thickness 0.15)
				)
				(justify left bottom)
			)
		)
		(property "Footprint" "antmicro-footprints:R_0402_1005Metric"
			(at 0 0 -90)
			(layer "F.Fab")
			(hide yes)
			(effects
				(font
					(size 1.27 1.27)
					(thickness 0.15)
				)
			)
		)
		(property "Datasheet" "https://www.bourns.com/docs/product-datasheets/cr.pdf"
			(at 0 0 -90)
			(layer "F.Fab")
			(hide yes)
			(effects
				(font
					(size 1.27 1.27)
					(thickness 0.15)
				)
			)
		)
		(property "Author" "Antmicro"
			(at -11.6 220 0)
			(layer "F.Fab")
			(hide yes)
			(effects
				(font
					(size 1 1)
					(thickness 0.15)
				)
			)
		)
		(property "License" "Apache-2.0"
			(at -11.6 220 0)
			(layer "F.Fab")
			(hide yes)
			(effects
				(font
					(size 1 1)
					(thickness 0.15)
				)
			)
		)
		(property "MPN" "CR0402-FX-1002GLF"
			(at -11.6 220 0)
			(layer "F.Fab")
			(hide yes)
			(effects
				(font
					(size 1 1)
					(thickness 0.15)
				)
			)
		)
		(property "Manufacturer" "Bourns"
			(at -11.6 220 0)
			(layer "F.Fab")
			(hide yes)
			(effects
				(font
					(size 1 1)
					(thickness 0.15)
				)
			)
		)
		(property "Tolerance" "1%"
			(at -11.6 220 0)
			(layer "F.Fab")
			(hide yes)
			(effects
				(font
					(size 1 1)
					(thickness 0.15)
				)
			)
		)
		(property "Val" "10k"
			(at -11.6 220 0)
			(layer "F.Fab")
			(hide yes)
			(effects
				(font
					(size 1 1)
					(thickness 0.15)
				)
			)
		)
		(sheetname "USB3")
		(sheetfile "usb3.kicad_sch")
		(attr smd)
		(fp_rect
			(start -0.925 -0.47)
			(end 0.925 0.47)
			(stroke
				(width 0.05)
				(type default)
			)
			(fill none)
			(layer "F.CrtYd")
		)
		(fp_rect
			(start -0.5 -0.25)
			(end 0.5 0.25)
			(stroke
				(width 0.15)
				(type solid)
			)
			(fill none)
			(layer "F.Fab")
		)
		(fp_text user "${REFERENCE}"
			(at -0.95 3.168 -90)
			(layer "F.Fab")
			(hide yes)
			(effects
				(font
					(size 0.7 0.7)
					(thickness 0.15)
				)
				(justify left bottom)
			)
		)
		(fp_text user "Author: Antmicro"
			(at -0.95 4.169 -90)
			(layer "F.Fab")
			(hide yes)
			(effects
				(font
					(size 0.7 0.7)
					(thickness 0.15)
				)
				(justify left bottom)
			)
		)
		(fp_text user "License: Apache-2.0"
			(at -0.95 5.169 -90)
			(layer "F.Fab")
			(hide yes)
			(effects
				(font
					(size 0.7 0.7)
					(thickness 0.15)
				)
				(justify left bottom)
			)
		)
		(pad "1" smd roundrect
			(at -0.48 0 270)
			(size 0.59 0.64)
			(layers "F.Cu" "F.Paste" "F.Mask")
			(roundrect_rratio 0.25)
			(net 562 "USBC1_PEN")
			(pintype "passive")
		)
		(pad "2" smd roundrect
			(at 0.48 0 270)
			(size 0.59 0.64)
			(layers "F.Cu" "F.Paste" "F.Mask")
			(roundrect_rratio 0.25)
			(net 284 "/USB3/USBC1_ID")
			(pintype "passive")
		)
	)
	(footprint "antmicro-footprints:SOT-523"
		(layer "F.Cu")
		(at 132.1 121.34 180)
		(property "Reference" "Q10"
			(at 1 -1.01 -90)
			(layer "F.SilkS")
			(effects
				(font
					(size 0.7 0.7)
					(thickness 0.15)
				)
				(justify left bottom)
			)
		)
		(property "Value" "PJE138K"
			(at 0.1 1.824 180)
			(layer "F.Fab")
			(effects
				(font
					(size 0.7 0.7)
					(thickness 0.15)
				)
				(justify left bottom)
			)
		)
		(property "Footprint" "antmicro-footprints:SOT-523"
			(at 0 0 180)
			(layer "F.Fab")
			(hide yes)
			(effects
				(font
					(size 1.27 1.27)
					(thickness 0.15)
				)
			)
		)
		(property "Datasheet" "https://www.mouser.com/datasheet/2/1057/PJE138K-1876698.pdf"
			(at 0 0 180)
			(layer "F.Fab")
			(hide yes)
			(effects
				(font
					(size 1.27 1.27)
					(thickness 0.15)
				)
			)
		)
		(property "Author" "Antmicro"
			(at 264.2 242.68 0)
			(layer "F.Fab")
			(hide yes)
			(effects
				(font
					(size 1 1)
					(thickness 0.15)
				)
			)
		)
		(property "License" "Apache-2.0"
			(at 264.2 242.68 0)
			(layer "F.Fab")
			(hide yes)
			(effects
				(font
					(size 1 1)
					(thickness 0.15)
				)
			)
		)
		(property "MPN" "PJE138K_R1_00001"
			(at 264.2 242.68 0)
			(layer "F.Fab")
			(hide yes)
			(effects
				(font
					(size 1 1)
					(thickness 0.15)
				)
			)
		)
		(property "Manufacturer" "PANJIT"
			(at 264.2 242.68 0)
			(layer "F.Fab")
			(hide yes)
			(effects
				(font
					(size 1 1)
					(thickness 0.15)
				)
			)
		)
		(sheetname "Peripherals")
		(sheetfile "peripherals.kicad_sch")
		(attr smd)
		(fp_line
			(start -0.277 -0.551)
			(end -0.277 -0.75)
			(stroke
				(width 0.15)
				(type solid)
			)
			(layer "F.SilkS")
		)
		(fp_line
			(start -0.725 -0.551)
			(end -0.277 -0.551)
			(stroke
				(width 0.15)
				(type solid)
			)
			(layer "F.SilkS")
		)
		(fp_line
			(start -0.927 -0.051)
			(end -0.927 -0.351)
			(stroke
				(width 0.15)
				(type solid)
			)
			(layer "F.SilkS")
		)
		(fp_line
			(start -0.927 -0.351)
			(end -0.725 -0.551)
			(stroke
				(width 0.15)
				(type solid)
			)
			(layer "F.SilkS")
		)
		(fp_circle
			(center -0.9652 0.9652)
			(end -0.9152 0.9652)
			(stroke
				(width 0.15)
				(type solid)
			)
			(fill solid)
			(layer "F.SilkS")
		)
		(fp_line
			(start 1.1 -1.16)
			(end 1.1 1.15)
			(stroke
				(width 0.05)
				(type solid)
			)
			(layer "F.CrtYd")
		)
		(fp_line
			(start -1.12 1.15)
			(end 1.1 1.15)
			(stroke
				(width 0.05)
				(type solid)
			)
			(layer "F.CrtYd")
		)
		(fp_line
			(start -1.12 -1.16)
			(end 1.1 -1.16)
			(stroke
				(width 0.05)
				(type solid)
			)
			(layer "F.CrtYd")
		)
		(fp_line
			(start -1.12 -1.16)
			(end -1.12 1.15)
			(stroke
				(width 0.05)
				(type solid)
			)
			(layer "F.CrtYd")
		)
		(fp_line
			(start 0.8 0.424)
			(end -0.802 0.424)
			(stroke
				(width 0.15)
				(type solid)
			)
			(layer "F.Fab")
		)
		(fp_line
			(start 0.8 -0.425)
			(end 0.8 0.424)
			(stroke
				(width 0.15)
				(type solid)
			)
			(layer "F.Fab")
		)
		(fp_line
			(start 0.8 -0.425)
			(end -0.652 -0.425)
			(stroke
				(width 0.15)
				(type solid)
			)
			(layer "F.Fab")
		)
		(fp_line
			(start -0.652 -0.425)
			(end -0.802 -0.276)
			(stroke
				(width 0.15)
				(type solid)
			)
			(layer "F.Fab")
		)
		(fp_line
			(start -0.802 -0.276)
			(end -0.802 0.424)
			(stroke
				(width 0.15)
				(type solid)
			)
			(layer "F.Fab")
		)
		(fp_circle
			(center -0.9652 0.9652)
			(end -0.9144 0.9652)
			(stroke
				(width 0.15)
				(type solid)
			)
			(fill none)
			(layer "F.Fab")
		)
		(fp_text user "Author: Antmicro"
			(at -1.12 6.224 180)
			(layer "F.Fab")
			(hide yes)
			(effects
				(font
					(size 0.7 0.7)
					(thickness 0.15)
				)
				(justify left bottom)
			)
		)
		(fp_text user "License: Apache-2.0"
			(at -1.12 5.024 180)
			(layer "F.Fab")
			(hide yes)
			(effects
				(font
					(size 0.7 0.7)
					(thickness 0.15)
				)
				(justify left bottom)
			)
		)
		(fp_text user "${REFERENCE}"
			(at -1.12 3.824 180)
			(layer "F.Fab")
			(hide yes)
			(effects
				(font
					(size 0.7 0.7)
					(thickness 0.15)
				)
				(justify left bottom)
			)
		)
		(pad "1" smd rect
			(at -0.5 0.65 180)
			(size 0.4 0.51)
			(layers "F.Cu" "F.Paste" "F.Mask")
			(net 44 "USER_LED1")
			(pinfunction "G")
			(pintype "passive")
		)
		(pad "2" smd rect
			(at 0.498 0.65 180)
			(size 0.4 0.51)
			(layers "F.Cu" "F.Paste" "F.Mask")
			(net 1 "GND")
			(pinfunction "S")
			(pintype "passive")
		)
		(pad "3" smd rect
			(at 0 -0.652 180)
			(size 0.4 0.51)
			(layers "F.Cu" "F.Paste" "F.Mask")
			(net 181 "Net-(D27-C)")
			(pinfunction "D")
			(pintype "passive")
		)
	)
)
